(kicad_pcb
	(version 20241229)
	(generator "pcbnew")
	(generator_version "9.0")
	(general
		(thickness 1.6296)
		(legacy_teardrops no)
	)
	(paper "A3")
	(title_block
		(title "Thunderbolt to 10GbE adapter")
		(date "2026-04-21")
		(rev "1.1.0")
		(company "Antmicro Ltd")
		(comment 1 "www.antmicro.com")
		(comment 9 "footprints 695-699 of 703")
	)
	(layers
		(0 "F.Cu" signal)
		(4 "In1.Cu" signal)
		(6 "In2.Cu" signal)
		(8 "In3.Cu" signal)
		(10 "In4.Cu" signal)
		(12 "In5.Cu" signal)
		(14 "In6.Cu" signal)
		(2 "B.Cu" signal)
		(9 "F.Adhes" user "F.Adhesive")
		(11 "B.Adhes" user "B.Adhesive")
		(13 "F.Paste" user)
		(15 "B.Paste" user)
		(5 "F.SilkS" user "F.Silkscreen")
		(7 "B.SilkS" user "B.Silkscreen")
		(1 "F.Mask" user)
		(3 "B.Mask" user)
		(17 "Dwgs.User" user "User.Drawings")
		(19 "Cmts.User" user "User.Comments")
		(21 "Eco1.User" user "User.Eco1")
		(23 "Eco2.User" user "User.Eco2")
		(25 "Edge.Cuts" user)
		(27 "Margin" user)
		(31 "F.CrtYd" user "F.Courtyard")
		(29 "B.CrtYd" user "B.Courtyard")
		(35 "F.Fab" user)
		(33 "B.Fab" user)
	)
	(footprint "antmicro-footprints:R_0402_1005Metric"
		(layer "B.Cu")
		(at 129.9 131.1 90)
		(descr "Resistor SMD 0402")
		(tags "resistor SMD 0402")
		(property "Reference" "R55"
			(at 8.1 20.250001 270)
			(layer "B.SilkS")
			(effects
				(font
					(size 0.7 0.7)
					(thickness 0.15)
				)
				(justify mirror)
			)
		)
		(property "Value" "R_1M_0402"
			(at -1.011843 -1.772047 270)
			(layer "B.Fab")
			(effects
				(font
					(size 0.7 0.7)
					(thickness 0.15)
				)
				(justify left bottom mirror)
			)
		)
		(property "Datasheet" "https://www.bourns.com/docs/product-datasheets/cr.pdf"
			(at 0 0 270)
			(layer "B.Fab")
			(hide yes)
			(effects
				(font
					(size 1.27 1.27)
					(thickness 0.15)
				)
				(justify mirror)
			)
		)
		(property "Description" "SMD Chip Resistor, 1 Mohm, ± 1%, 62.5 mW, 0402 [1005 Metric], Thick Film, General Purpose"
			(at 0 0 270)
			(layer "B.Fab")
			(hide yes)
			(effects
				(font
					(size 1.27 1.27)
					(thickness 0.15)
				)
				(justify mirror)
			)
		)
		(property "MPN" "CR0402-FX-1004GLF"
			(at 0 0 90)
			(unlocked yes)
			(layer "B.Fab")
			(hide yes)
			(effects
				(font
					(size 1 1)
					(thickness 0.15)
				)
				(justify mirror)
			)
		)
		(property "Manufacturer" "Bourns"
			(at 0 0 90)
			(unlocked yes)
			(layer "B.Fab")
			(hide yes)
			(effects
				(font
					(size 1 1)
					(thickness 0.15)
				)
				(justify mirror)
			)
		)
		(property "License" "Apache-2.0"
			(at 0 0 90)
			(unlocked yes)
			(layer "B.Fab")
			(hide yes)
			(effects
				(font
					(size 1 1)
					(thickness 0.15)
				)
				(justify mirror)
			)
		)
		(property "Val" "1M"
			(at 0 0 90)
			(unlocked yes)
			(layer "B.Fab")
			(hide yes)
			(effects
				(font
					(size 1 1)
					(thickness 0.15)
				)
				(justify mirror)
			)
		)
		(property "Tolerance" "1%"
			(at 0 0 90)
			(unlocked yes)
			(layer "B.Fab")
			(hide yes)
			(effects
				(font
					(size 1 1)
					(thickness 0.15)
				)
				(justify mirror)
			)
		)
		(property "Author" "Antmicro"
			(at 0 0 90)
			(unlocked yes)
			(layer "B.Fab")
			(hide yes)
			(effects
				(font
					(size 1 1)
					(thickness 0.15)
				)
				(justify mirror)
			)
		)
		(sheetname "/TB Controller/")
		(sheetfile "tb.kicad_sch")
		(attr smd)
		(fp_rect
			(start -0.925 0.47)
			(end 0.925 -0.47)
			(stroke
				(width 0.05)
				(type default)
			)
			(fill no)
			(layer "B.CrtYd")
		)
		(fp_rect
			(start -0.5 0.25)
			(end 0.5 -0.25)
			(stroke
				(width 0.15)
				(type solid)
			)
			(fill no)
			(layer "B.Fab")
		)
		(fp_text user "License: Apache-2.0"
			(at -0.95 -5.169 270)
			(layer "B.Fab")
			(effects
				(font
					(size 0.7 0.7)
					(thickness 0.15)
				)
				(justify left bottom mirror)
			)
		)
		(fp_text user "Author: Antmicro"
			(at -0.95 -4.169 270)
			(layer "B.Fab")
			(effects
				(font
					(size 0.7 0.7)
					(thickness 0.15)
				)
				(justify left bottom mirror)
			)
		)
		(fp_text user "${REFERENCE}"
			(at -0.95 -3.168 270)
			(layer "B.Fab")
			(effects
				(font
					(size 0.7 0.7)
					(thickness 0.15)
				)
				(justify left bottom mirror)
			)
		)
		(pad "1" smd roundrect
			(at -0.48 0 90)
			(size 0.59 0.64)
			(layers "B.Cu" "B.Mask" "B.Paste")
			(roundrect_rratio 0.25)
			(net 23 "GND")
			(pintype "passive")
		)
		(pad "2" smd roundrect
			(at 0.48 0 90)
			(size 0.59 0.64)
			(layers "B.Cu" "B.Mask" "B.Paste")
			(roundrect_rratio 0.25)
			(net 383 "/PD and TB DC-DC/LSX_1.LSX_R2P")
			(pintype "passive")
		)
	)
	(footprint "antmicro-footprints:Fiducial_1mm_Mask2mm"
		(layer "B.Cu")
		(at 130.5 151.5 180)
		(descr "Circular Fiducial, 1mm bare copper, 3mm soldermask opening")
		(tags "fiducial")
		(property "Reference" "FD8"
			(at 1.25 -0.25 0)
			(layer "B.SilkS")
			(effects
				(font
					(size 0.7 0.7)
					(thickness 0.15)
				)
				(justify left bottom mirror)
			)
		)
		(property "Value" "Fiducial_1mm_Mask2mm"
			(at 0 -2.2 0)
			(layer "B.Fab")
			(effects
				(font
					(size 0.7 0.7)
					(thickness 0.15)
				)
				(justify left bottom mirror)
			)
		)
		(property "Description" "Fiducial mask"
			(at 0 0 0)
			(layer "B.Fab")
			(hide yes)
			(effects
				(font
					(size 1.27 1.27)
					(thickness 0.15)
				)
				(justify mirror)
			)
		)
		(property "Author" "Antmicro"
			(at 0 0 180)
			(unlocked yes)
			(layer "B.Fab")
			(hide yes)
			(effects
				(font
					(size 1 1)
					(thickness 0.15)
				)
				(justify mirror)
			)
		)
		(property "License" "Apache-2.0"
			(at 0 0 180)
			(unlocked yes)
			(layer "B.Fab")
			(hide yes)
			(effects
				(font
					(size 1 1)
					(thickness 0.15)
				)
				(justify mirror)
			)
		)
		(sheetname "/")
		(sheetfile "thunderbolt-to-10gbe-adapter.kicad_sch")
		(attr exclude_from_pos_files exclude_from_bom)
		(fp_circle
			(center 0 0)
			(end 1.24 0)
			(stroke
				(width 0.05)
				(type solid)
			)
			(fill no)
			(layer "B.CrtYd")
		)
		(fp_circle
			(center 0 0)
			(end 0.999 0)
			(stroke
				(width 0.15)
				(type solid)
			)
			(fill no)
			(layer "B.Fab")
		)
		(fp_text user "Author: Antmicro"
			(at -1.25 -5.803 0)
			(layer "B.Fab")
			(effects
				(font
					(size 0.7 0.7)
					(thickness 0.15)
				)
				(justify left bottom mirror)
			)
		)
		(fp_text user "License: Apache-2.0"
			(at -1.25 -7.003 0)
			(layer "B.Fab")
			(effects
				(font
					(size 0.7 0.7)
					(thickness 0.15)
				)
				(justify left bottom mirror)
			)
		)
		(fp_text user "${REFERENCE}"
			(at -1.25 -4.603 0)
			(layer "B.Fab")
			(effects
				(font
					(size 0.7 0.7)
					(thickness 0.15)
				)
				(justify left bottom mirror)
			)
		)
		(pad "" smd circle
			(at 0 0 180)
			(size 1 1)
			(layers "B.Cu" "B.Mask")
			(solder_mask_margin 0.5)
			(clearance 0.5)
		)
	)
	(footprint "antmicro-footprints:R_0402_1005Metric"
		(layer "B.Cu")
		(at 180.8 70)
		(descr "Resistor SMD 0402")
		(tags "resistor SMD 0402")
		(property "Reference" "R83"
			(at 3 0.4 180)
			(layer "B.SilkS")
			(effects
				(font
					(size 0.7 0.7)
					(thickness 0.15)
				)
				(justify left bottom mirror)
			)
		)
		(property "Value" "R_330R_0402"
			(at -1.011843 -1.772047 180)
			(layer "B.Fab")
			(effects
				(font
					(size 0.7 0.7)
					(thickness 0.15)
				)
				(justify left bottom mirror)
			)
		)
		(property "Datasheet" "https://www.bourns.com/docs/product-datasheets/cr.pdf"
			(at 0 0 180)
			(layer "B.Fab")
			(hide yes)
			(effects
				(font
					(size 1.27 1.27)
					(thickness 0.15)
				)
				(justify mirror)
			)
		)
		(property "Description" "SMD Chip Resistor, 330 ohm, ± 1%, 62.5 mW, 0402 [1005 Metric], Thick Film, General Purpose"
			(at 0 0 180)
			(layer "B.Fab")
			(hide yes)
			(effects
				(font
					(size 1.27 1.27)
					(thickness 0.15)
				)
				(justify mirror)
			)
		)
		(property "MPN" "CR0402-FX-3300GLF"
			(at 0 0 0)
			(unlocked yes)
			(layer "B.Fab")
			(hide yes)
			(effects
				(font
					(size 1 1)
					(thickness 0.15)
				)
				(justify mirror)
			)
		)
		(property "Manufacturer" "Bourns"
			(at 0 0 0)
			(unlocked yes)
			(layer "B.Fab")
			(hide yes)
			(effects
				(font
					(size 1 1)
					(thickness 0.15)
				)
				(justify mirror)
			)
		)
		(property "License" "Apache-2.0"
			(at 0 0 0)
			(unlocked yes)
			(layer "B.Fab")
			(hide yes)
			(effects
				(font
					(size 1 1)
					(thickness 0.15)
				)
				(justify mirror)
			)
		)
		(property "Author" "Antmicro"
			(at 0 0 0)
			(unlocked yes)
			(layer "B.Fab")
			(hide yes)
			(effects
				(font
					(size 1 1)
					(thickness 0.15)
				)
				(justify mirror)
			)
		)
		(property "Val" "330R"
			(at 0 0 0)
			(unlocked yes)
			(layer "B.Fab")
			(hide yes)
			(effects
				(font
					(size 1 1)
					(thickness 0.15)
				)
				(justify mirror)
			)
		)
		(property "Tolerance" "1%"
			(at 0 0 0)
			(unlocked yes)
			(layer "B.Fab")
			(hide yes)
			(effects
				(font
					(size 1 1)
					(thickness 0.15)
				)
				(justify mirror)
			)
		)
		(sheetname "/X710 DCDC converters/")
		(sheetfile "DCDC_converters_X710.kicad_sch")
		(attr smd)
		(fp_rect
			(start -0.925 0.47)
			(end 0.925 -0.47)
			(stroke
				(width 0.05)
				(type default)
			)
			(fill no)
			(layer "B.CrtYd")
		)
		(fp_rect
			(start -0.5 0.25)
			(end 0.5 -0.25)
			(stroke
				(width 0.15)
				(type solid)
			)
			(fill no)
			(layer "B.Fab")
		)
		(fp_text user "Author: Antmicro"
			(at -0.95 -4.169 180)
			(layer "B.Fab")
			(effects
				(font
					(size 0.7 0.7)
					(thickness 0.15)
				)
				(justify left bottom mirror)
			)
		)
		(fp_text user "${REFERENCE}"
			(at -0.95 -3.168 180)
			(layer "B.Fab")
			(effects
				(font
					(size 0.7 0.7)
					(thickness 0.15)
				)
				(justify left bottom mirror)
			)
		)
		(fp_text user "License: Apache-2.0"
			(at -0.95 -5.169 180)
			(layer "B.Fab")
			(effects
				(font
					(size 0.7 0.7)
					(thickness 0.15)
				)
				(justify left bottom mirror)
			)
		)
		(pad "1" smd roundrect
			(at -0.48 0)
			(size 0.59 0.64)
			(layers "B.Cu" "B.Mask" "B.Paste")
			(roundrect_rratio 0.25)
			(net 23 "GND")
			(pintype "passive")
		)
		(pad "2" smd roundrect
			(at 0.48 0)
			(size 0.59 0.64)
			(layers "B.Cu" "B.Mask" "B.Paste")
			(roundrect_rratio 0.25)
			(net 414 "Net-(D6-C)")
			(pintype "passive")
		)
	)
	(footprint "antmicro-footprints:C_0402_1005Metric"
		(layer "B.Cu")
		(at 126.549999 124.075 90)
		(descr "Capacitor SMD 0402")
		(tags "capacitor SMD 0402")
		(property "Reference" "C57"
			(at 7.700002 21.900002 270)
			(layer "B.SilkS")
			(effects
				(font
					(size 0.7 0.7)
					(thickness 0.15)
				)
				(justify mirror)
			)
		)
		(property "Value" "C_1u_0402"
			(at -1.022927 -2.155213 270)
			(layer "B.Fab")
			(effects
				(font
					(size 0.7 0.7)
					(thickness 0.15)
				)
				(justify left bottom mirror)
			)
		)
		(property "Datasheet" "https://product.tdk.com/en/search/capacitor/ceramic/mlcc/info?part_no=C1005X6S1A105K050BC"
			(at 0 0 270)
			(layer "B.Fab")
			(hide yes)
			(effects
				(font
					(size 1.27 1.27)
					(thickness 0.15)
				)
				(justify mirror)
			)
		)
		(property "Description" "SMD Multilayer Ceramic Capacitor, 1 µF, 10 V, 0402 [1005 Metric], ± 10%, X6S, C"
			(at 0 0 270)
			(layer "B.Fab")
			(hide yes)
			(effects
				(font
					(size 1.27 1.27)
					(thickness 0.15)
				)
				(justify mirror)
			)
		)
		(property "MPN" "C1005X6S1A105K050BC"
			(at 0 0 90)
			(unlocked yes)
			(layer "B.Fab")
			(hide yes)
			(effects
				(font
					(size 1 1)
					(thickness 0.15)
				)
				(justify mirror)
			)
		)
		(property "Manufacturer" "TDK"
			(at 0 0 90)
			(unlocked yes)
			(layer "B.Fab")
			(hide yes)
			(effects
				(font
					(size 1 1)
					(thickness 0.15)
				)
				(justify mirror)
			)
		)
		(property "License" "Apache-2.0"
			(at 0 0 90)
			(unlocked yes)
			(layer "B.Fab")
			(hide yes)
			(effects
				(font
					(size 1 1)
					(thickness 0.15)
				)
				(justify mirror)
			)
		)
		(property "Val" "1u"
			(at 0 0 90)
			(unlocked yes)
			(layer "B.Fab")
			(hide yes)
			(effects
				(font
					(size 1 1)
					(thickness 0.15)
				)
				(justify mirror)
			)
		)
		(property "Voltage" ""
			(at 0 0 90)
			(unlocked yes)
			(layer "B.Fab")
			(hide yes)
			(effects
				(font
					(size 1 1)
					(thickness 0.15)
				)
				(justify mirror)
			)
		)
		(property "Dielectric" ""
			(at 0 0 90)
			(unlocked yes)
			(layer "B.Fab")
			(hide yes)
			(effects
				(font
					(size 1 1)
					(thickness 0.15)
				)
				(justify mirror)
			)
		)
		(property "Author" "Antmicro"
			(at 0 0 90)
			(unlocked yes)
			(layer "B.Fab")
			(hide yes)
			(effects
				(font
					(size 1 1)
					(thickness 0.15)
				)
				(justify mirror)
			)
		)
		(sheetname "/TB Controller - Power/")
		(sheetfile "tb-power.kicad_sch")
		(attr smd)
		(fp_rect
			(start -0.925 0.47)
			(end 0.925 -0.47)
			(stroke
				(width 0.05)
				(type default)
			)
			(fill no)
			(layer "B.CrtYd")
		)
		(fp_line
			(start 0.504 -0.248)
			(end -0.494 -0.248)
			(stroke
				(width 0.15)
				(type solid)
			)
			(layer "B.Fab")
		)
		(fp_line
			(start -0.494 -0.248)
			(end -0.494 0.25)
			(stroke
				(width 0.15)
				(type solid)
			)
			(layer "B.Fab")
		)
		(fp_line
			(start 0.504 0.25)
			(end 0.504 -0.248)
			(stroke
				(width 0.15)
				(type solid)
			)
			(layer "B.Fab")
		)
		(fp_line
			(start -0.494 0.25)
			(end 0.504 0.25)
			(stroke
				(width 0.15)
				(type solid)
			)
			(layer "B.Fab")
		)
		(fp_text user "Author: Antmicro"
			(at -0.939 -3.399 270)
			(layer "B.Fab")
			(effects
				(font
					(size 0.7 0.7)
					(thickness 0.15)
				)
				(justify left bottom mirror)
			)
		)
		(fp_text user "License: Apache-2.0"
			(at -0.939 -5.799 270)
			(layer "B.Fab")
			(effects
				(font
					(size 0.7 0.7)
					(thickness 0.15)
				)
				(justify left bottom mirror)
			)
		)
		(fp_text user "${REFERENCE}"
			(at -0.939 -4.599 270)
			(layer "B.Fab")
			(effects
				(font
					(size 0.7 0.7)
					(thickness 0.15)
				)
				(justify left bottom mirror)
			)
		)
		(pad "1" smd roundrect
			(at -0.48 0 90)
			(size 0.59 0.64)
			(layers "B.Cu" "B.Mask" "B.Paste")
			(roundrect_rratio 0.25)
			(net 23 "GND")
			(pintype "passive")
		)
		(pad "2" smd roundrect
			(at 0.48 0 90)
			(size 0.59 0.64)
			(layers "B.Cu" "B.Mask" "B.Paste")
			(roundrect_rratio 0.25)
			(net 403 "Net-(C55-Pad2)")
			(pintype "passive")
		)
	)
	(footprint "antmicro-footprints:C_0402_1005Metric"
		(layer "B.Cu")
		(at 132.860001 133 90)
		(descr "Capacitor SMD 0402")
		(tags "capacitor SMD 0402")
		(property "Reference" "C20"
			(at 8.339997 19.525001 270)
			(layer "B.SilkS")
			(effects
				(font
					(size 0.7 0.7)
					(thickness 0.15)
				)
				(justify mirror)
			)
		)
		(property "Value" "C_2u2_0402"
			(at -1.022927 -2.155213 270)
			(layer "B.Fab")
			(effects
				(font
					(size 0.7 0.7)
					(thickness 0.15)
				)
				(justify left bottom mirror)
			)
		)
		(property "Datasheet" "https://product.tdk.com/en/search/capacitor/ceramic/mlcc/info?part_no=C1005X5R1A225K050BC"
			(at 0 0 270)
			(layer "B.Fab")
			(hide yes)
			(effects
				(font
					(size 1.27 1.27)
					(thickness 0.15)
				)
				(justify mirror)
			)
		)
		(property "Description" "SMD Multilayer Ceramic Capacitor, 2.2 µF, 10 V, 0402 [1005 Metric], ± 10%, X5R, C"
			(at 0 0 270)
			(layer "B.Fab")
			(hide yes)
			(effects
				(font
					(size 1.27 1.27)
					(thickness 0.15)
				)
				(justify mirror)
			)
		)
		(property "MPN" "C1005X5R1A225K050BC"
			(at 0 0 90)
			(unlocked yes)
			(layer "B.Fab")
			(hide yes)
			(effects
				(font
					(size 1 1)
					(thickness 0.15)
				)
				(justify mirror)
			)
		)
		(property "Manufacturer" "TDK"
			(at 0 0 90)
			(unlocked yes)
			(layer "B.Fab")
			(hide yes)
			(effects
				(font
					(size 1 1)
					(thickness 0.15)
				)
				(justify mirror)
			)
		)
		(property "License" "Apache-2.0"
			(at 0 0 90)
			(unlocked yes)
			(layer "B.Fab")
			(hide yes)
			(effects
				(font
					(size 1 1)
					(thickness 0.15)
				)
				(justify mirror)
			)
		)
		(property "Val" "2u2"
			(at 0 0 90)
			(unlocked yes)
			(layer "B.Fab")
			(hide yes)
			(effects
				(font
					(size 1 1)
					(thickness 0.15)
				)
				(justify mirror)
			)
		)
		(property "Voltage" ""
			(at 0 0 90)
			(unlocked yes)
			(layer "B.Fab")
			(hide yes)
			(effects
				(font
					(size 1 1)
					(thickness 0.15)
				)
				(justify mirror)
			)
		)
		(property "Dielectric" ""
			(at 0 0 90)
			(unlocked yes)
			(layer "B.Fab")
			(hide yes)
			(effects
				(font
					(size 1 1)
					(thickness 0.15)
				)
				(justify mirror)
			)
		)
		(property "Author" "Antmicro"
			(at 0 0 90)
			(unlocked yes)
			(layer "B.Fab")
			(hide yes)
			(effects
				(font
					(size 1 1)
					(thickness 0.15)
				)
				(justify mirror)
			)
		)
		(sheetname "/PD and TB DC-DC/")
		(sheetfile "PD_and_TB_DC_DC.kicad_sch")
		(attr smd)
		(fp_rect
			(start -0.925 0.47)
			(end 0.925 -0.47)
			(stroke
				(width 0.05)
				(type default)
			)
			(fill no)
			(layer "B.CrtYd")
		)
		(fp_line
			(start 0.504 -0.248)
			(end -0.494 -0.248)
			(stroke
				(width 0.15)
				(type solid)
			)
			(layer "B.Fab")
		)
		(fp_line
			(start -0.494 -0.248)
			(end -0.494 0.25)
			(stroke
				(width 0.15)
				(type solid)
			)
			(layer "B.Fab")
		)
		(fp_line
			(start 0.504 0.25)
			(end 0.504 -0.248)
			(stroke
				(width 0.15)
				(type solid)
			)
			(layer "B.Fab")
		)
		(fp_line
			(start -0.494 0.25)
			(end 0.504 0.25)
			(stroke
				(width 0.15)
				(type solid)
			)
			(layer "B.Fab")
		)
		(fp_text user "Author: Antmicro"
			(at -0.939 -3.399 270)
			(layer "B.Fab")
			(effects
				(font
					(size 0.7 0.7)
					(thickness 0.15)
				)
				(justify left bottom mirror)
			)
		)
		(fp_text user "License: Apache-2.0"
			(at -0.939 -5.799 270)
			(layer "B.Fab")
			(effects
				(font
					(size 0.7 0.7)
					(thickness 0.15)
				)
				(justify left bottom mirror)
			)
		)
		(fp_text user "${REFERENCE}"
			(at -0.939 -4.599 270)
			(layer "B.Fab")
			(effects
				(font
					(size 0.7 0.7)
					(thickness 0.15)
				)
				(justify left bottom mirror)
			)
		)
		(pad "1" smd roundrect
			(at -0.48 0 90)
			(size 0.59 0.64)
			(layers "B.Cu" "B.Mask" "B.Paste")
			(roundrect_rratio 0.25)
			(net 172 "Net-(U3-LDO_1V8A)")
			(pintype "passive")
		)
		(pad "2" smd roundrect
			(at 0.48 0 90)
			(size 0.59 0.64)
			(layers "B.Cu" "B.Mask" "B.Paste")
			(roundrect_rratio 0.25)
			(net 23 "GND")
			(pintype "passive")
		)
	)
)
